(kicad_pcb
	(version 20260206)
	(generator "pcbnew")
	(generator_version "10.0")
	(general
		(thickness 1.6)
		(legacy_teardrops no)
	)
	(paper "A4")
	(title_block
		(title "12092022_DA0F0TMDCD0_F0T_Management_Board_D_brd_V3_OCP.brd")
		(comment 1 "Grand Teton / footprints 915-919 of 1440")
	)
	(layers
		(0 "F.Cu" signal "TOP")
		(4 "In1.Cu" signal "GND")
		(6 "In2.Cu" signal "IN1")
		(8 "In3.Cu" signal "GND1")
		(10 "In4.Cu" signal "IN2")
		(12 "In5.Cu" signal "VCC")
		(14 "In6.Cu" signal "VCC1")
		(16 "In7.Cu" signal "IN3")
		(18 "In8.Cu" signal "GND2")
		(20 "In9.Cu" signal "IN4")
		(22 "In10.Cu" signal "GND3")
		(2 "B.Cu" signal "BOTTOM")
		(9 "F.Adhes" user "F.Adhesive")
		(11 "B.Adhes" user "B.Adhesive")
		(13 "F.Paste" user "Package Geometry/Pastemask Top")
		(15 "B.Paste" user "Package Geometry/Pastemask Bottom")
		(5 "F.SilkS" user "Ref Des/Silkscreen Top")
		(7 "B.SilkS" user "Ref Des/Silkscreen Bottom")
		(1 "F.Mask" user "Board Geometry/Soldermask Top")
		(3 "B.Mask" user "Board Geometry/Soldermask Bottom")
		(17 "Dwgs.User" user "User.Drawings")
		(19 "Cmts.User" user "User.Comments")
		(21 "Eco1.User" user "User.Eco1")
		(23 "Eco2.User" user "User.Eco2")
		(25 "Edge.Cuts" user "Board Geometry/Outline")
		(27 "Margin" user)
		(31 "F.CrtYd" user "Package Geometry/Place Bound Top")
		(29 "B.CrtYd" user "Package Geometry/Place Bound Bottom")
		(35 "F.Fab" user "Ref Des/Assembly Top")
		(33 "B.Fab" user "Ref Des/Assembly Bottom")
	)
	(footprint ""
		(layer "B.Cu")
		(at 50.974244 -49.38141 180)
		(property "Reference" "C103"
			(at 0 0 0)
			(layer "B.SilkS")
			(hide yes)
			(effects
				(font
					(size 1.27 1.27)
				)
				(justify mirror)
			)
		)
		(property "Value" ""
			(at 0 0 0)
			(layer "B.Fab")
			(effects
				(font
					(size 1.27 1.27)
				)
				(justify mirror)
			)
		)
		(duplicate_pad_numbers_are_jumpers no)
		(fp_line
			(start 0.7874 0.4064)
			(end 0.7874 -0.4064)
			(stroke
				(width 0.1524)
				(type default)
			)
			(layer "B.SilkS")
		)
		(fp_line
			(start 0.7874 -0.4064)
			(end -0.7874 -0.4064)
			(stroke
				(width 0.1524)
				(type default)
			)
			(layer "B.SilkS")
		)
		(fp_line
			(start -0.7874 0.4064)
			(end 0.7874 0.4064)
			(stroke
				(width 0.1524)
				(type default)
			)
			(layer "B.SilkS")
		)
		(fp_line
			(start -0.7874 -0.4064)
			(end -0.7874 0.4064)
			(stroke
				(width 0.1524)
				(type default)
			)
			(layer "B.SilkS")
		)
		(fp_line
			(start 0.67945 0.3048)
			(end 0.67945 -0.305054)
			(stroke
				(width 0.1)
				(type default)
			)
			(layer "B.Fab")
		)
		(fp_line
			(start 0.67945 -0.305054)
			(end 0.12065 -0.305054)
			(stroke
				(width 0.1)
				(type default)
			)
			(layer "B.Fab")
		)
		(fp_line
			(start 0.12065 0.3048)
			(end 0.67945 0.3048)
			(stroke
				(width 0.1)
				(type default)
			)
			(layer "B.Fab")
		)
		(fp_line
			(start 0.12065 0.2794)
			(end 0.12065 0.3048)
			(stroke
				(width 0.1)
				(type default)
			)
			(layer "B.Fab")
		)
		(fp_line
			(start 0.12065 -0.2794)
			(end -0.12065 -0.2794)
			(stroke
				(width 0.1)
				(type default)
			)
			(layer "B.Fab")
		)
		(fp_line
			(start 0.12065 -0.305054)
			(end 0.12065 -0.2794)
			(stroke
				(width 0.1)
				(type default)
			)
			(layer "B.Fab")
		)
		(fp_line
			(start -0.120396 0.3048)
			(end -0.120396 0.2794)
			(stroke
				(width 0.1)
				(type default)
			)
			(layer "B.Fab")
		)
		(fp_line
			(start -0.120396 0.2794)
			(end 0.12065 0.2794)
			(stroke
				(width 0.1)
				(type default)
			)
			(layer "B.Fab")
		)
		(fp_line
			(start -0.12065 -0.2794)
			(end -0.12065 -0.3048)
			(stroke
				(width 0.1)
				(type default)
			)
			(layer "B.Fab")
		)
		(fp_line
			(start -0.12065 -0.3048)
			(end -0.67945 -0.3048)
			(stroke
				(width 0.1)
				(type default)
			)
			(layer "B.Fab")
		)
		(fp_line
			(start -0.67945 0.3048)
			(end -0.120396 0.3048)
			(stroke
				(width 0.1)
				(type default)
			)
			(layer "B.Fab")
		)
		(fp_line
			(start -0.67945 -0.3048)
			(end -0.67945 0.3048)
			(stroke
				(width 0.1)
				(type default)
			)
			(layer "B.Fab")
		)
		(pad "1" smd circle
			(at 0.40005 0)
			(size 0 0)
			(layers "B.Cu" "B.Mask" "B.Paste")
			(net "P1V2_AUX")
		)
		(pad "2" smd circle
			(at -0.40005 0)
			(size 0 0)
			(layers "B.Cu" "B.Mask" "B.Paste")
			(net "GND")
		)
	)
	(footprint ""
		(layer "B.Cu")
		(at 48.940466 -79.960216 180)
		(property "Reference" "U30"
			(at -3.447034 3.439414 0)
			(unlocked yes)
			(layer "B.SilkS")
			(effects
				(font
					(size 0.7874 0.5842)
					(thickness 0.1524)
				)
				(justify left mirror)
			)
		)
		(property "Value" ""
			(at 0 0 0)
			(layer "B.Fab")
			(effects
				(font
					(size 1.27 1.27)
				)
				(justify mirror)
			)
		)
		(duplicate_pad_numbers_are_jumpers no)
		(fp_line
			(start 2.0066 2.5654)
			(end 2.0066 -2.5654)
			(stroke
				(width 0.1524)
				(type default)
			)
			(layer "B.SilkS")
		)
		(fp_line
			(start 2.0066 -2.5654)
			(end 0.5842 -2.5654)
			(stroke
				(width 0.1524)
				(type default)
			)
			(layer "B.SilkS")
		)
		(fp_line
			(start 0.5842 -2.5654)
			(end 0 -1.9812)
			(stroke
				(width 0.1524)
				(type default)
			)
			(layer "B.SilkS")
		)
		(fp_line
			(start 0 -1.9812)
			(end -0.5842 -2.5654)
			(stroke
				(width 0.1524)
				(type default)
			)
			(layer "B.SilkS")
		)
		(fp_line
			(start -0.5842 -2.5654)
			(end -2.0066 -2.5654)
			(stroke
				(width 0.1524)
				(type default)
			)
			(layer "B.SilkS")
		)
		(fp_line
			(start -2.0066 2.5654)
			(end 2.0066 2.5654)
			(stroke
				(width 0.1524)
				(type default)
			)
			(layer "B.SilkS")
		)
		(fp_line
			(start -2.0066 -2.5654)
			(end -2.0066 2.5654)
			(stroke
				(width 0.1524)
				(type default)
			)
			(layer "B.SilkS")
		)
		(fp_poly
			(pts
				(xy 3.955288 -2.275078) (xy 4.971288 -2.783078) (xy 4.971288 -1.767078)
			)
			(stroke
				(width 0)
				(type default)
			)
			(fill yes)
			(layer "B.SilkS")
		)
		(fp_line
			(start 3.7338 2.5654)
			(end 3.6703 2.5654)
			(stroke
				(width 0.1)
				(type default)
			)
			(layer "B.Fab")
		)
		(fp_line
			(start 3.7338 -2.5654)
			(end 3.7338 2.5654)
			(stroke
				(width 0.1)
				(type default)
			)
			(layer "B.Fab")
		)
		(fp_line
			(start 3.6703 2.5654)
			(end -3.6703 2.5654)
			(stroke
				(width 0.1)
				(type default)
			)
			(layer "B.Fab")
		)
		(fp_line
			(start 3.6703 -2.5654)
			(end 3.7338 -2.5654)
			(stroke
				(width 0.1)
				(type default)
			)
			(layer "B.Fab")
		)
		(fp_line
			(start -3.6703 2.5654)
			(end -3.7338 2.5654)
			(stroke
				(width 0.1)
				(type default)
			)
			(layer "B.Fab")
		)
		(fp_line
			(start -3.6703 -2.5654)
			(end 3.6703 -2.5654)
			(stroke
				(width 0.1)
				(type default)
			)
			(layer "B.Fab")
		)
		(fp_line
			(start -3.7338 2.5654)
			(end -3.7338 -2.5654)
			(stroke
				(width 0.1)
				(type default)
			)
			(layer "B.Fab")
		)
		(fp_line
			(start -3.7338 -2.5654)
			(end -3.6703 -2.5654)
			(stroke
				(width 0.1)
				(type default)
			)
			(layer "B.Fab")
		)
		(fp_poly
			(pts
				(xy 3.955288 -2.275078) (xy 4.971288 -2.783078) (xy 4.971288 -1.767078)
			)
			(stroke
				(width 0)
				(type default)
			)
			(fill yes)
			(layer "B.Fab")
		)
		(pad "1" smd rect
			(at 2.921 -2.275078 90)
			(size 0.3556 1.4986)
			(layers "B.Cu" "B.Mask" "B.Paste")
			(net "FM_BMC_BIOS_MUX_CS_SPI_R_SEL_0")
		)
		(pad "2" smd rect
			(at 2.921 -1.625092 90)
			(size 0.3556 1.4986)
			(layers "B.Cu" "B.Mask" "B.Paste")
			(net "SPI_SYS_MUX_MOSI")
		)
		(pad "3" smd rect
			(at 2.921 -0.975106 90)
			(size 0.3556 1.4986)
			(layers "B.Cu" "B.Mask" "B.Paste")
			(net "SPI_BMC_BIOS_ROM_R_MOSI")
		)
		(pad "4" smd rect
			(at 2.921 -0.32512 90)
			(size 0.3556 1.4986)
			(layers "B.Cu" "B.Mask" "B.Paste")
			(net "SPI_PCH_MUXED_IO0")
		)
		(pad "5" smd rect
			(at 2.921 0.32512 90)
			(size 0.3556 1.4986)
			(layers "B.Cu" "B.Mask" "B.Paste")
			(net "SPI_SYS_MUX_HOLD_IO3")
		)
		(pad "6" smd rect
			(at 2.921 0.975106 90)
			(size 0.3556 1.4986)
			(layers "B.Cu" "B.Mask" "B.Paste")
			(net "SPI_BMC_BIOS_ROM_R_IO3")
		)
		(pad "7" smd rect
			(at 2.921 1.625092 90)
			(size 0.3556 1.4986)
			(layers "B.Cu" "B.Mask" "B.Paste")
			(net "SPI_PCH_MUXED_IO3")
		)
		(pad "8" smd rect
			(at 2.921 2.275078 90)
			(size 0.3556 1.4986)
			(layers "B.Cu" "B.Mask" "B.Paste")
			(net "GND")
		)
		(pad "9" smd rect
			(at -2.921 2.275078 90)
			(size 0.3556 1.4986)
			(layers "B.Cu" "B.Mask" "B.Paste")
			(net "SPI_PCH_MUXED_CLK")
		)
		(pad "10" smd rect
			(at -2.921 1.625092 90)
			(size 0.3556 1.4986)
			(layers "B.Cu" "B.Mask" "B.Paste")
			(net "SPI_BMC_BIOS_ROM_R_CLK")
		)
		(pad "11" smd rect
			(at -2.921 0.975106 90)
			(size 0.3556 1.4986)
			(layers "B.Cu" "B.Mask" "B.Paste")
			(net "SPI_SYS_MUX_CLK")
		)
		(pad "12" smd rect
			(at -2.921 0.32512 90)
			(size 0.3556 1.4986)
			(layers "B.Cu" "B.Mask" "B.Paste")
			(net "TP_BIOS_MUX0_PIN12")
		)
		(pad "13" smd rect
			(at -2.921 -0.32512 90)
			(size 0.3556 1.4986)
			(layers "B.Cu" "B.Mask" "B.Paste")
			(net "TP_BIOS_MUX0_PIN13")
		)
		(pad "14" smd rect
			(at -2.921 -0.975106 90)
			(size 0.3556 1.4986)
			(layers "B.Cu" "B.Mask" "B.Paste")
			(net "TP_BIOS_MUX0_PIN14")
		)
		(pad "15" smd rect
			(at -2.921 -1.625092 90)
			(size 0.3556 1.4986)
			(layers "B.Cu" "B.Mask" "B.Paste")
			(net "PD_BIOS_MUX_EN_N")
		)
		(pad "16" smd rect
			(at -2.921 -2.275078 90)
			(size 0.3556 1.4986)
			(layers "B.Cu" "B.Mask" "B.Paste")
			(net "P3V3_AUX")
		)
	)
	(footprint ""
		(layer "B.Cu")
		(at 62.103 -52.832 -90)
		(property "Reference" "C22"
			(at 0 0 90)
			(layer "B.SilkS")
			(hide yes)
			(effects
				(font
					(size 1.27 1.27)
				)
				(justify mirror)
			)
		)
		(property "Value" ""
			(at 0 0 90)
			(layer "B.Fab")
			(effects
				(font
					(size 1.27 1.27)
				)
				(justify mirror)
			)
		)
		(duplicate_pad_numbers_are_jumpers no)
		(fp_line
			(start -0.7874 0.4064)
			(end 0.7874 0.4064)
			(stroke
				(width 0.1524)
				(type default)
			)
			(layer "B.SilkS")
		)
		(fp_line
			(start 0.7874 0.4064)
			(end 0.7874 -0.4064)
			(stroke
				(width 0.1524)
				(type default)
			)
			(layer "B.SilkS")
		)
		(fp_line
			(start -0.7874 -0.4064)
			(end -0.7874 0.4064)
			(stroke
				(width 0.1524)
				(type default)
			)
			(layer "B.SilkS")
		)
		(fp_line
			(start 0.7874 -0.4064)
			(end -0.7874 -0.4064)
			(stroke
				(width 0.1524)
				(type default)
			)
			(layer "B.SilkS")
		)
		(fp_line
			(start -0.67945 0.3048)
			(end -0.120396 0.3048)
			(stroke
				(width 0.1)
				(type default)
			)
			(layer "B.Fab")
		)
		(fp_line
			(start -0.120396 0.3048)
			(end -0.120396 0.2794)
			(stroke
				(width 0.1)
				(type default)
			)
			(layer "B.Fab")
		)
		(fp_line
			(start 0.12065 0.3048)
			(end 0.67945 0.3048)
			(stroke
				(width 0.1)
				(type default)
			)
			(layer "B.Fab")
		)
		(fp_line
			(start 0.67945 0.3048)
			(end 0.67945 -0.305054)
			(stroke
				(width 0.1)
				(type default)
			)
			(layer "B.Fab")
		)
		(fp_line
			(start -0.120396 0.2794)
			(end 0.12065 0.2794)
			(stroke
				(width 0.1)
				(type default)
			)
			(layer "B.Fab")
		)
		(fp_line
			(start 0.12065 0.2794)
			(end 0.12065 0.3048)
			(stroke
				(width 0.1)
				(type default)
			)
			(layer "B.Fab")
		)
		(fp_line
			(start -0.12065 -0.2794)
			(end -0.12065 -0.3048)
			(stroke
				(width 0.1)
				(type default)
			)
			(layer "B.Fab")
		)
		(fp_line
			(start 0.12065 -0.2794)
			(end -0.12065 -0.2794)
			(stroke
				(width 0.1)
				(type default)
			)
			(layer "B.Fab")
		)
		(fp_line
			(start -0.67945 -0.3048)
			(end -0.67945 0.3048)
			(stroke
				(width 0.1)
				(type default)
			)
			(layer "B.Fab")
		)
		(fp_line
			(start -0.12065 -0.3048)
			(end -0.67945 -0.3048)
			(stroke
				(width 0.1)
				(type default)
			)
			(layer "B.Fab")
		)
		(fp_line
			(start 0.12065 -0.305054)
			(end 0.12065 -0.2794)
			(stroke
				(width 0.1)
				(type default)
			)
			(layer "B.Fab")
		)
		(fp_line
			(start 0.67945 -0.305054)
			(end 0.12065 -0.305054)
			(stroke
				(width 0.1)
				(type default)
			)
			(layer "B.Fab")
		)
		(pad "1" smd circle
			(at 0.40005 0 90)
			(size 0 0)
			(layers "B.Cu" "B.Mask" "B.Paste")
			(net "P0V6_DDR_VREF_AUX")
		)
		(pad "2" smd circle
			(at -0.40005 0 90)
			(size 0 0)
			(layers "B.Cu" "B.Mask" "B.Paste")
			(net "GND")
		)
	)
	(footprint ""
		(layer "B.Cu")
		(at 25.019 -92.456)
		(property "Reference" "R307"
			(at 0 0 0)
			(layer "B.SilkS")
			(hide yes)
			(effects
				(font
					(size 1.27 1.27)
				)
				(justify mirror)
			)
		)
		(property "Value" ""
			(at 0 0 0)
			(layer "B.Fab")
			(effects
				(font
					(size 1.27 1.27)
				)
				(justify mirror)
			)
		)
		(duplicate_pad_numbers_are_jumpers no)
		(fp_line
			(start -0.7874 -0.4064)
			(end -0.7874 0.4064)
			(stroke
				(width 0.1524)
				(type default)
			)
			(layer "B.SilkS")
		)
		(fp_line
			(start -0.7874 0.4064)
			(end 0.7874 0.4064)
			(stroke
				(width 0.1524)
				(type default)
			)
			(layer "B.SilkS")
		)
		(fp_line
			(start 0.7874 -0.4064)
			(end -0.7874 -0.4064)
			(stroke
				(width 0.1524)
				(type default)
			)
			(layer "B.SilkS")
		)
		(fp_line
			(start 0.7874 0.4064)
			(end 0.7874 -0.4064)
			(stroke
				(width 0.1524)
				(type default)
			)
			(layer "B.SilkS")
		)
		(fp_line
			(start -0.67945 -0.3048)
			(end -0.67945 0.3048)
			(stroke
				(width 0.1)
				(type default)
			)
			(layer "B.Fab")
		)
		(fp_line
			(start -0.67945 0.3048)
			(end -0.120396 0.3048)
			(stroke
				(width 0.1)
				(type default)
			)
			(layer "B.Fab")
		)
		(fp_line
			(start -0.12065 -0.3048)
			(end -0.67945 -0.3048)
			(stroke
				(width 0.1)
				(type default)
			)
			(layer "B.Fab")
		)
		(fp_line
			(start -0.12065 -0.2794)
			(end -0.12065 -0.3048)
			(stroke
				(width 0.1)
				(type default)
			)
			(layer "B.Fab")
		)
		(fp_line
			(start -0.120396 0.2794)
			(end 0.12065 0.2794)
			(stroke
				(width 0.1)
				(type default)
			)
			(layer "B.Fab")
		)
		(fp_line
			(start -0.120396 0.3048)
			(end -0.120396 0.2794)
			(stroke
				(width 0.1)
				(type default)
			)
			(layer "B.Fab")
		)
		(fp_line
			(start 0.12065 -0.305054)
			(end 0.12065 -0.2794)
			(stroke
				(width 0.1)
				(type default)
			)
			(layer "B.Fab")
		)
		(fp_line
			(start 0.12065 -0.2794)
			(end -0.12065 -0.2794)
			(stroke
				(width 0.1)
				(type default)
			)
			(layer "B.Fab")
		)
		(fp_line
			(start 0.12065 0.2794)
			(end 0.12065 0.3048)
			(stroke
				(width 0.1)
				(type default)
			)
			(layer "B.Fab")
		)
		(fp_line
			(start 0.12065 0.3048)
			(end 0.67945 0.3048)
			(stroke
				(width 0.1)
				(type default)
			)
			(layer "B.Fab")
		)
		(fp_line
			(start 0.67945 -0.305054)
			(end 0.12065 -0.305054)
			(stroke
				(width 0.1)
				(type default)
			)
			(layer "B.Fab")
		)
		(fp_line
			(start 0.67945 0.3048)
			(end 0.67945 -0.305054)
			(stroke
				(width 0.1)
				(type default)
			)
			(layer "B.Fab")
		)
		(pad "1" smd circle
			(at 0.40005 0 180)
			(size 0 0)
			(layers "B.Cu" "B.Mask" "B.Paste")
			(net "P3V3_AUX")
		)
		(pad "2" smd circle
			(at -0.40005 0 180)
			(size 0 0)
			(layers "B.Cu" "B.Mask" "B.Paste")
			(net "VCCIO4")
		)
	)
	(footprint ""
		(layer "B.Cu")
		(at 14.351 -106.426 90)
		(property "Reference" "R220"
			(at 0 0 90)
			(layer "B.SilkS")
			(hide yes)
			(effects
				(font
					(size 1.27 1.27)
				)
				(justify mirror)
			)
		)
		(property "Value" ""
			(at 0 0 90)
			(layer "B.Fab")
			(effects
				(font
					(size 1.27 1.27)
				)
				(justify mirror)
			)
		)
		(duplicate_pad_numbers_are_jumpers no)
		(fp_line
			(start 0.7874 -0.4064)
			(end -0.7874 -0.4064)
			(stroke
				(width 0.1524)
				(type default)
			)
			(layer "B.SilkS")
		)
		(fp_line
			(start -0.7874 -0.4064)
			(end -0.7874 0.4064)
			(stroke
				(width 0.1524)
				(type default)
			)
			(layer "B.SilkS")
		)
		(fp_line
			(start 0.7874 0.4064)
			(end 0.7874 -0.4064)
			(stroke
				(width 0.1524)
				(type default)
			)
			(layer "B.SilkS")
		)
		(fp_line
			(start -0.7874 0.4064)
			(end 0.7874 0.4064)
			(stroke
				(width 0.1524)
				(type default)
			)
			(layer "B.SilkS")
		)
		(fp_line
			(start 0.67945 -0.305054)
			(end 0.12065 -0.305054)
			(stroke
				(width 0.1)
				(type default)
			)
			(layer "B.Fab")
		)
		(fp_line
			(start 0.12065 -0.305054)
			(end 0.12065 -0.2794)
			(stroke
				(width 0.1)
				(type default)
			)
			(layer "B.Fab")
		)
		(fp_line
			(start -0.12065 -0.3048)
			(end -0.67945 -0.3048)
			(stroke
				(width 0.1)
				(type default)
			)
			(layer "B.Fab")
		)
		(fp_line
			(start -0.67945 -0.3048)
			(end -0.67945 0.3048)
			(stroke
				(width 0.1)
				(type default)
			)
			(layer "B.Fab")
		)
		(fp_line
			(start 0.12065 -0.2794)
			(end -0.12065 -0.2794)
			(stroke
				(width 0.1)
				(type default)
			)
			(layer "B.Fab")
		)
		(fp_line
			(start -0.12065 -0.2794)
			(end -0.12065 -0.3048)
			(stroke
				(width 0.1)
				(type default)
			)
			(layer "B.Fab")
		)
		(fp_line
			(start 0.12065 0.2794)
			(end 0.12065 0.3048)
			(stroke
				(width 0.1)
				(type default)
			)
			(layer "B.Fab")
		)
		(fp_line
			(start -0.120396 0.2794)
			(end 0.12065 0.2794)
			(stroke
				(width 0.1)
				(type default)
			)
			(layer "B.Fab")
		)
		(fp_line
			(start 0.67945 0.3048)
			(end 0.67945 -0.305054)
			(stroke
				(width 0.1)
				(type default)
			)
			(layer "B.Fab")
		)
		(fp_line
			(start 0.12065 0.3048)
			(end 0.67945 0.3048)
			(stroke
				(width 0.1)
				(type default)
			)
			(layer "B.Fab")
		)
		(fp_line
			(start -0.120396 0.3048)
			(end -0.120396 0.2794)
			(stroke
				(width 0.1)
				(type default)
			)
			(layer "B.Fab")
		)
		(fp_line
			(start -0.67945 0.3048)
			(end -0.120396 0.3048)
			(stroke
				(width 0.1)
				(type default)
			)
			(layer "B.Fab")
		)
		(pad "1" smd circle
			(at 0.40005 0 270)
			(size 0 0)
			(layers "B.Cu" "B.Mask" "B.Paste")
			(net "FM_BMC_UARTSW_MSB_N")
		)
		(pad "2" smd circle
			(at -0.40005 0 270)
			(size 0 0)
			(layers "B.Cu" "B.Mask" "B.Paste")
			(net "FM_UARTSW_MSB_N")
		)
	)
)
